FILE_TYPE = MACRO_DRAWING;
SET COLOR_WIRE YELLOW;
SET COLOR_PROP MONO;
SET COLOR_DOT WHITE;
SET COLOR_ARC YELLOW;
SET COLOR_BODY GREEN;
SET COLOR_NOTE MONO;
SET PROP_DISPLAY VALUE;
SET PAGE_NUMBER P15;
FORCEADD INTEL_CORP_BPAGE..1
(75 2025);
FORCEPROP 1 LAST CDS_CON_LAST_MODIFIED Fri Jun 16 17:48:02 2017
J 0
(-1350 2350);
PAINT ORANGE (-1350 2350);
DISPLAY INVISIBLE (-1350 2350);
FORCEPROP 2 LAST CUSTOM_TXT_CDS <XR_PAGE_TITLE>
J 0
(-7815 7275);
DISPLAY 0.638298 (-7815 7275);
PAINT PINK (-7815 7275);
DISPLAY INVISIBLE (-7815 7275);
FORCEPROP 2 LAST CUSTOM_TXT_CDS <CON_LAST_MODIFIED>
J 0
(-3925 2125);
PAINT ORANGE (-3925 2125);
FORCEPROP 2 LAST CUSTOM_TXT_CDS <CURRENT_DESIGN_SHEET> OF <TOTAL_DESIGN_SHEETS>
J 0
(-425 2050);
PAINT ORANGE (-425 2050);
FORCEPROP 1 LAST SCH_TITLE PWRGD/RESET
J 0
(-7875 2075);
DISPLAY 1.212766 (-7875 2075);
PAINT ORANGE (-7875 2075);
FORCEPROP 2 LAST PAGE_BORDER TRUE
J 0
(-7815 7275);
DISPLAY 0.638298 (-7815 7275);
PAINT PINK (-7815 7275);
DISPLAY INVISIBLE (-7815 7275);
FORCEPROP 2 LAST CDS_LIB mstr_symbols
J 0
(75 2025);
PAINT MONO (75 2025);
DISPLAY INVISIBLE (75 2025);
FORCEPROP 1 LAST COMMENT_BODY TRUE
J 0
(87 2037);
DISPLAY 0.468085 (87 2037);
PAINT GREEN (87 2037);
DISPLAY INVISIBLE (87 2037);
FORCEPROP 2 LAST CDS_XR_PAGE_TITLE CR-15 : @BASEBOARD_FAB2_LIB.BASEBOARD_FAB2(SCH_1):PAGE15
J 0
(-7815 7275);
DISPLAY 0.638298 (-7815 7275);
PAINT PINK (-7815 7275);
DISPLAY INVISIBLE (-7815 7275);
FORCENOTE
$CDS_IMAGE|TiogaPass_PWRGD_RST_Block_diagram_20160412.jpg|8750|5000
(-3900 4700) 0;
DISPLAY LEFT (-3900 4700);
QUIT
